# SCM (Grand Teton) — schematic netlist excerpt (pin names and nets, part order shuffled) for the footprints in the layout excerpt that follows; sources: Cadence DE-HDL packaged netlist, KiCad conversion of 12092022_DA0F0TMDCD0_F0T_Management_Board_D_brd_V3_OCP.brd

R289  Q_RES  10K 1% CHIP  pkg 0402LF  page 22 : A = P3V3_RGM ; B = BJT_Q3_C
R706  Q_RES  4.7K 1% CHIP  pkg 0402LF  page 12 : A = P3V3_AUX ; B = FM_BMC_DBP_PRESENT_N

(kicad_pcb
	(version 20260206)
	(generator "pcbnew")
	(generator_version "10.0")
	(general
		(thickness 1.6)
		(legacy_teardrops no)
	)
	(paper "A4")
	(title_block
		(title "12092022_DA0F0TMDCD0_F0T_Management_Board_D_brd_V3_OCP.brd")
		(comment 1 "Grand Teton / footprints 324-325 of 1440")
	)
	(layers
		(0 "F.Cu" signal "TOP")
		(4 "In1.Cu" signal "GND")
		(6 "In2.Cu" signal "IN1")
		(8 "In3.Cu" signal "GND1")
		(10 "In4.Cu" signal "IN2")
		(12 "In5.Cu" signal "VCC")
		(14 "In6.Cu" signal "VCC1")
		(16 "In7.Cu" signal "IN3")
		(18 "In8.Cu" signal "GND2")
		(20 "In9.Cu" signal "IN4")
		(22 "In10.Cu" signal "GND3")
		(2 "B.Cu" signal "BOTTOM")
		(9 "F.Adhes" user "F.Adhesive")
		(11 "B.Adhes" user "B.Adhesive")
		(13 "F.Paste" user "Package Geometry/Pastemask Top")
		(15 "B.Paste" user "Package Geometry/Pastemask Bottom")
		(5 "F.SilkS" user "Ref Des/Silkscreen Top")
		(7 "B.SilkS" user "Ref Des/Silkscreen Bottom")
		(1 "F.Mask" user "Board Geometry/Soldermask Top")
		(3 "B.Mask" user "Board Geometry/Soldermask Bottom")
		(17 "Dwgs.User" user "User.Drawings")
		(19 "Cmts.User" user "User.Comments")
		(21 "Eco1.User" user "User.Eco1")
		(23 "Eco2.User" user "User.Eco2")
		(25 "Edge.Cuts" user "Board Geometry/Outline")
		(27 "Margin" user)
		(31 "F.CrtYd" user "Package Geometry/Place Bound Top")
		(29 "B.CrtYd" user "Package Geometry/Place Bound Bottom")
		(35 "F.Fab" user "Ref Des/Assembly Top")
		(33 "B.Fab" user "Ref Des/Assembly Bottom")
	)
	(footprint ""
		(layer "F.Cu")
		(at 49.2125 -96.012 90)
		(property "Reference" "R289"
			(at 0 0 90)
			(layer "F.SilkS")
			(hide yes)
			(effects
				(font
					(size 1.27 1.27)
				)
			)
		)
		(property "Value" ""
			(at 0 0 90)
			(layer "F.Fab")
			(effects
				(font
					(size 1.27 1.27)
				)
			)
		)
		(duplicate_pad_numbers_are_jumpers no)
		(fp_line
			(start 0.7874 -0.4064)
			(end 0.7874 0.4064)
			(stroke
				(width 0.1524)
				(type default)
			)
			(layer "F.SilkS")
		)
		(fp_line
			(start -0.7874 -0.4064)
			(end 0.7874 -0.4064)
			(stroke
				(width 0.1524)
				(type default)
			)
			(layer "F.SilkS")
		)
		(fp_line
			(start 0.7874 0.4064)
			(end -0.7874 0.4064)
			(stroke
				(width 0.1524)
				(type default)
			)
			(layer "F.SilkS")
		)
		(fp_line
			(start -0.7874 0.4064)
			(end -0.7874 -0.4064)
			(stroke
				(width 0.1524)
				(type default)
			)
			(layer "F.SilkS")
		)
		(fp_line
			(start -0.12065 -0.305054)
			(end -0.12065 -0.2794)
			(stroke
				(width 0.1)
				(type default)
			)
			(layer "F.Fab")
		)
		(fp_line
			(start -0.67945 -0.305054)
			(end -0.12065 -0.305054)
			(stroke
				(width 0.1)
				(type default)
			)
			(layer "F.Fab")
		)
		(fp_line
			(start 0.67945 -0.3048)
			(end 0.67945 0.3048)
			(stroke
				(width 0.1)
				(type default)
			)
			(layer "F.Fab")
		)
		(fp_line
			(start 0.12065 -0.3048)
			(end 0.67945 -0.3048)
			(stroke
				(width 0.1)
				(type default)
			)
			(layer "F.Fab")
		)
		(fp_line
			(start 0.12065 -0.2794)
			(end 0.12065 -0.3048)
			(stroke
				(width 0.1)
				(type default)
			)
			(layer "F.Fab")
		)
		(fp_line
			(start -0.12065 -0.2794)
			(end 0.12065 -0.2794)
			(stroke
				(width 0.1)
				(type default)
			)
			(layer "F.Fab")
		)
		(fp_line
			(start 0.120396 0.2794)
			(end -0.12065 0.2794)
			(stroke
				(width 0.1)
				(type default)
			)
			(layer "F.Fab")
		)
		(fp_line
			(start -0.12065 0.2794)
			(end -0.12065 0.3048)
			(stroke
				(width 0.1)
				(type default)
			)
			(layer "F.Fab")
		)
		(fp_line
			(start 0.67945 0.3048)
			(end 0.120396 0.3048)
			(stroke
				(width 0.1)
				(type default)
			)
			(layer "F.Fab")
		)
		(fp_line
			(start 0.120396 0.3048)
			(end 0.120396 0.2794)
			(stroke
				(width 0.1)
				(type default)
			)
			(layer "F.Fab")
		)
		(fp_line
			(start -0.12065 0.3048)
			(end -0.67945 0.3048)
			(stroke
				(width 0.1)
				(type default)
			)
			(layer "F.Fab")
		)
		(fp_line
			(start -0.67945 0.3048)
			(end -0.67945 -0.305054)
			(stroke
				(width 0.1)
				(type default)
			)
			(layer "F.Fab")
		)
		(pad "1" smd circle
			(at -0.40005 0 90)
			(size 0 0)
			(layers "F.Cu" "F.Mask" "F.Paste")
			(net "P3V3_RGM")
		)
		(pad "2" smd circle
			(at 0.40005 0 90)
			(size 0 0)
			(layers "F.Cu" "F.Mask" "F.Paste")
			(net "BJT_Q3_C")
		)
	)
	(footprint ""
		(layer "F.Cu")
		(at 42.828464 -30.867604 90)
		(property "Reference" "R706"
			(at 0 0 90)
			(layer "F.SilkS")
			(hide yes)
			(effects
				(font
					(size 1.27 1.27)
				)
			)
		)
		(property "Value" ""
			(at 0 0 90)
			(layer "F.Fab")
			(effects
				(font
					(size 1.27 1.27)
				)
			)
		)
		(duplicate_pad_numbers_are_jumpers no)
		(fp_line
			(start 0.7874 -0.4064)
			(end 0.7874 0.4064)
			(stroke
				(width 0.1524)
				(type default)
			)
			(layer "F.SilkS")
		)
		(fp_line
			(start -0.7874 -0.4064)
			(end 0.7874 -0.4064)
			(stroke
				(width 0.1524)
				(type default)
			)
			(layer "F.SilkS")
		)
		(fp_line
			(start 0.7874 0.4064)
			(end -0.7874 0.4064)
			(stroke
				(width 0.1524)
				(type default)
			)
			(layer "F.SilkS")
		)
		(fp_line
			(start -0.7874 0.4064)
			(end -0.7874 -0.4064)
			(stroke
				(width 0.1524)
				(type default)
			)
			(layer "F.SilkS")
		)
		(fp_line
			(start -0.12065 -0.305054)
			(end -0.12065 -0.2794)
			(stroke
				(width 0.1)
				(type default)
			)
			(layer "F.Fab")
		)
		(fp_line
			(start -0.67945 -0.305054)
			(end -0.12065 -0.305054)
			(stroke
				(width 0.1)
				(type default)
			)
			(layer "F.Fab")
		)
		(fp_line
			(start 0.67945 -0.3048)
			(end 0.67945 0.3048)
			(stroke
				(width 0.1)
				(type default)
			)
			(layer "F.Fab")
		)
		(fp_line
			(start 0.12065 -0.3048)
			(end 0.67945 -0.3048)
			(stroke
				(width 0.1)
				(type default)
			)
			(layer "F.Fab")
		)
		(fp_line
			(start 0.12065 -0.2794)
			(end 0.12065 -0.3048)
			(stroke
				(width 0.1)
				(type default)
			)
			(layer "F.Fab")
		)
		(fp_line
			(start -0.12065 -0.2794)
			(end 0.12065 -0.2794)
			(stroke
				(width 0.1)
				(type default)
			)
			(layer "F.Fab")
		)
		(fp_line
			(start 0.120396 0.2794)
			(end -0.12065 0.2794)
			(stroke
				(width 0.1)
				(type default)
			)
			(layer "F.Fab")
		)
		(fp_line
			(start -0.12065 0.2794)
			(end -0.12065 0.3048)
			(stroke
				(width 0.1)
				(type default)
			)
			(layer "F.Fab")
		)
		(fp_line
			(start 0.67945 0.3048)
			(end 0.120396 0.3048)
			(stroke
				(width 0.1)
				(type default)
			)
			(layer "F.Fab")
		)
		(fp_line
			(start 0.120396 0.3048)
			(end 0.120396 0.2794)
			(stroke
				(width 0.1)
				(type default)
			)
			(layer "F.Fab")
		)
		(fp_line
			(start -0.12065 0.3048)
			(end -0.67945 0.3048)
			(stroke
				(width 0.1)
				(type default)
			)
			(layer "F.Fab")
		)
		(fp_line
			(start -0.67945 0.3048)
			(end -0.67945 -0.305054)
			(stroke
				(width 0.1)
				(type default)
			)
			(layer "F.Fab")
		)
		(pad "1" smd circle
			(at -0.40005 0 90)
			(size 0 0)
			(layers "F.Cu" "F.Mask" "F.Paste")
			(net "P3V3_AUX")
		)
		(pad "2" smd circle
			(at 0.40005 0 90)
			(size 0 0)
			(layers "F.Cu" "F.Mask" "F.Paste")
			(net "FM_BMC_DBP_PRESENT_N")
		)
	)
)
